(kicad_pcb
	(version 20241229)
	(generator "pcbnew")
	(generator_version "9.0")
	(general
		(thickness 1.6)
		(legacy_teardrops no)
	)
	(paper "A4")
	(title_block
		(title "OCuLink to PCIe adapter")
		(date "2025-06-18")
		(rev "1.0.0")
		(company "Antmicro Ltd")
		(comment 1 "www.antmicro.com")
		(comment 9 "footprints 137-140 of 159")
	)
	(layers
		(0 "F.Cu" signal)
		(4 "In1.Cu" signal)
		(6 "In2.Cu" signal)
		(2 "B.Cu" signal)
		(9 "F.Adhes" user "F.Adhesive")
		(11 "B.Adhes" user "B.Adhesive")
		(13 "F.Paste" user)
		(15 "B.Paste" user)
		(5 "F.SilkS" user "F.Silkscreen")
		(7 "B.SilkS" user "B.Silkscreen")
		(1 "F.Mask" user)
		(3 "B.Mask" user)
		(17 "Dwgs.User" user "User.Drawings")
		(19 "Cmts.User" user "User.Comments")
		(21 "Eco1.User" user "User.Eco1")
		(23 "Eco2.User" user "User.Eco2")
		(25 "Edge.Cuts" user)
		(27 "Margin" user)
		(31 "F.CrtYd" user "F.Courtyard")
		(29 "B.CrtYd" user "B.Courtyard")
		(35 "F.Fab" user)
		(33 "B.Fab" user)
	)
	(footprint "antmicro-footprints:SOT-23-3"
		(layer "F.Cu")
		(at 131.72 156.499998)
		(property "Reference" "Q3"
			(at 1.08 -0.699998 180)
			(layer "F.SilkS")
			(effects
				(font
					(size 0.7 0.7)
					(thickness 0.15)
				)
				(justify left bottom)
			)
		)
		(property "Value" "BSS138-7-F"
			(at -1.9 2.7 0)
			(layer "F.Fab")
			(effects
				(font
					(size 0.7 0.7)
					(thickness 0.15)
				)
				(justify left bottom)
			)
		)
		(property "Datasheet" "https://www.diodes.com/assets/Datasheets/ds30144.pdf"
			(at 0 0 0)
			(layer "F.Fab")
			(hide yes)
			(effects
				(font
					(size 1.27 1.27)
					(thickness 0.15)
				)
			)
		)
		(property "Description" "Power MOSFET, N Channel, 50 V, 200 mA, 1.4 ohm, SOT-23, Surface Mount"
			(at 0 0 0)
			(layer "F.Fab")
			(hide yes)
			(effects
				(font
					(size 1.27 1.27)
					(thickness 0.15)
				)
			)
		)
		(property "MPN" "BSS138-7-F"
			(at 0 0 0)
			(unlocked yes)
			(layer "F.Fab")
			(hide yes)
			(effects
				(font
					(size 1 1)
					(thickness 0.15)
				)
			)
		)
		(property "Manufacturer" "Diodes Incorporated"
			(at 0 0 0)
			(unlocked yes)
			(layer "F.Fab")
			(hide yes)
			(effects
				(font
					(size 1 1)
					(thickness 0.15)
				)
			)
		)
		(property "Author" "Antmicro"
			(at 0 0 0)
			(unlocked yes)
			(layer "F.Fab")
			(hide yes)
			(effects
				(font
					(size 1 1)
					(thickness 0.15)
				)
			)
		)
		(property "License" "Apache-2.0"
			(at 0 0 0)
			(unlocked yes)
			(layer "F.Fab")
			(hide yes)
			(effects
				(font
					(size 1 1)
					(thickness 0.15)
				)
			)
		)
		(sheetname "/Power/")
		(sheetfile "power.kicad_sch")
		(attr smd)
		(fp_line
			(start -1.45 -1.35)
			(end -0.85 -1.35)
			(stroke
				(width 0.15)
				(type solid)
			)
			(layer "F.SilkS")
		)
		(fp_line
			(start -0.85 -1.35)
			(end -0.7 -1.5)
			(stroke
				(width 0.15)
				(type solid)
			)
			(layer "F.SilkS")
		)
		(fp_line
			(start -0.7 1.5)
			(end -0.7 1.35)
			(stroke
				(width 0.15)
				(type solid)
			)
			(layer "F.SilkS")
		)
		(fp_line
			(start 0.7 -1.5)
			(end -0.7 -1.5)
			(stroke
				(width 0.15)
				(type solid)
			)
			(layer "F.SilkS")
		)
		(fp_line
			(start 0.7 -0.4)
			(end 0.7 -1.5)
			(stroke
				(width 0.15)
				(type solid)
			)
			(layer "F.SilkS")
		)
		(fp_line
			(start 0.7 0.4)
			(end 0.7 1.5)
			(stroke
				(width 0.15)
				(type solid)
			)
			(layer "F.SilkS")
		)
		(fp_line
			(start 0.7 1.5)
			(end -0.7 1.5)
			(stroke
				(width 0.15)
				(type solid)
			)
			(layer "F.SilkS")
		)
		(fp_line
			(start -1.75 -0.5)
			(end -1.75 -1.4)
			(stroke
				(width 0.05)
				(type solid)
			)
			(layer "F.CrtYd")
		)
		(fp_line
			(start -1.75 0.5)
			(end -0.85 0.5)
			(stroke
				(width 0.05)
				(type solid)
			)
			(layer "F.CrtYd")
		)
		(fp_line
			(start -1.75 1.4)
			(end -1.75 0.5)
			(stroke
				(width 0.05)
				(type solid)
			)
			(layer "F.CrtYd")
		)
		(fp_line
			(start -0.9 -1.6)
			(end -0.9 -1.4)
			(stroke
				(width 0.05)
				(type solid)
			)
			(layer "F.CrtYd")
		)
		(fp_line
			(start -0.9 -1.6)
			(end 0.825 -1.6)
			(stroke
				(width 0.05)
				(type solid)
			)
			(layer "F.CrtYd")
		)
		(fp_line
			(start -0.9 -1.4)
			(end -1.75 -1.4)
			(stroke
				(width 0.05)
				(type solid)
			)
			(layer "F.CrtYd")
		)
		(fp_line
			(start -0.85 -0.5)
			(end -1.75 -0.5)
			(stroke
				(width 0.05)
				(type solid)
			)
			(layer "F.CrtYd")
		)
		(fp_line
			(start -0.85 0.5)
			(end -0.85 -0.5)
			(stroke
				(width 0.05)
				(type solid)
			)
			(layer "F.CrtYd")
		)
		(fp_line
			(start -0.85 1.4)
			(end -1.75 1.4)
			(stroke
				(width 0.05)
				(type solid)
			)
			(layer "F.CrtYd")
		)
		(fp_line
			(start -0.85 1.65)
			(end -0.85 1.4)
			(stroke
				(width 0.05)
				(type solid)
			)
			(layer "F.CrtYd")
		)
		(fp_line
			(start 0.825 -1.6)
			(end 0.825 -0.45)
			(stroke
				(width 0.05)
				(type solid)
			)
			(layer "F.CrtYd")
		)
		(fp_line
			(start 0.825 -0.45)
			(end 1.75 -0.45)
			(stroke
				(width 0.05)
				(type solid)
			)
			(layer "F.CrtYd")
		)
		(fp_line
			(start 0.85 0.45)
			(end 0.85 1.65)
			(stroke
				(width 0.05)
				(type solid)
			)
			(layer "F.CrtYd")
		)
		(fp_line
			(start 0.85 1.65)
			(end -0.85 1.65)
			(stroke
				(width 0.05)
				(type solid)
			)
			(layer "F.CrtYd")
		)
		(fp_line
			(start 1.75 -0.45)
			(end 1.75 0.45)
			(stroke
				(width 0.05)
				(type solid)
			)
			(layer "F.CrtYd")
		)
		(fp_line
			(start 1.75 0.45)
			(end 0.85 0.45)
			(stroke
				(width 0.05)
				(type solid)
			)
			(layer "F.CrtYd")
		)
		(fp_line
			(start -0.712 -1.325)
			(end -0.712 1.523)
			(stroke
				(width 0.15)
				(type solid)
			)
			(layer "F.Fab")
		)
		(fp_line
			(start -0.712 1.519)
			(end 0.688 1.519)
			(stroke
				(width 0.15)
				(type solid)
			)
			(layer "F.Fab")
		)
		(fp_line
			(start -0.437 -1.526)
			(end -0.712 -1.325)
			(stroke
				(width 0.15)
				(type solid)
			)
			(layer "F.Fab")
		)
		(fp_line
			(start -0.437 -1.526)
			(end 0.688 -1.526)
			(stroke
				(width 0.15)
				(type solid)
			)
			(layer "F.Fab")
		)
		(fp_line
			(start 0.688 1.519)
			(end 0.688 -1.52)
			(stroke
				(width 0.15)
				(type solid)
			)
			(layer "F.Fab")
		)
		(fp_text user "License: Apache-2.0"
			(at -1.8 6.8 0)
			(layer "F.Fab")
			(effects
				(font
					(size 0.7 0.7)
					(thickness 0.15)
				)
				(justify left bottom)
			)
		)
		(fp_text user "Author: Antmicro"
			(at -1.837 5.3 0)
			(layer "F.Fab")
			(effects
				(font
					(size 0.7 0.7)
					(thickness 0.15)
				)
				(justify left bottom)
			)
		)
		(fp_text user "${REFERENCE}"
			(at 0.000001 0.025 0)
			(layer "F.Fab")
			(effects
				(font
					(size 0.7 0.7)
					(thickness 0.15)
				)
				(justify left bottom)
			)
		)
		(pad "1" smd roundrect
			(at -1.1 -0.951)
			(size 1 0.6)
			(layers "F.Cu" "F.Mask" "F.Paste")
			(roundrect_rratio 0.15)
			(net 172 "/Power/~{PERST}")
			(pinfunction "G")
			(pintype "input")
		)
		(pad "2" smd roundrect
			(at -1.1 0.949)
			(size 1 0.6)
			(layers "F.Cu" "F.Mask" "F.Paste")
			(roundrect_rratio 0.15)
			(net 66 "GND")
			(pinfunction "S")
			(pintype "passive")
		)
		(pad "3" smd roundrect
			(at 1.1 -0.0005)
			(size 1 0.6)
			(layers "F.Cu" "F.Mask" "F.Paste")
			(roundrect_rratio 0.15)
			(net 161 "Net-(Q3-D)")
			(pinfunction "D")
			(pintype "passive")
		)
	)
	(footprint "antmicro-footprints:C_0402_1005Metric"
		(layer "F.Cu")
		(at 120.5 134.8)
		(descr "Capacitor SMD 0402")
		(tags "capacitor SMD 0402")
		(property "Reference" "C7"
			(at -3.3 0.4 180)
			(layer "F.SilkS")
			(effects
				(font
					(size 0.7 0.7)
					(thickness 0.15)
				)
				(justify left bottom)
			)
		)
		(property "Value" "C_1u_25V_0402"
			(at -1.022927 2.155213 0)
			(layer "F.Fab")
			(effects
				(font
					(size 0.7 0.7)
					(thickness 0.15)
				)
				(justify left bottom)
			)
		)
		(property "Datasheet" "https://www.murata.com/products/productdetail?partno=GRM155R61E105KE11%23"
			(at 0 0 0)
			(layer "F.Fab")
			(hide yes)
			(effects
				(font
					(size 1.27 1.27)
					(thickness 0.15)
				)
			)
		)
		(property "Description" "SMD Multilayer Ceramic Capacitor, 1 µF, 25 V, 0402 [1005 Metric], ± 10%, X5R, GRM Series"
			(at 0 0 0)
			(layer "F.Fab")
			(hide yes)
			(effects
				(font
					(size 1.27 1.27)
					(thickness 0.15)
				)
			)
		)
		(property "MPN" "GRM155R61E105KE11J"
			(at 0 0 0)
			(unlocked yes)
			(layer "F.Fab")
			(hide yes)
			(effects
				(font
					(size 1 1)
					(thickness 0.15)
				)
			)
		)
		(property "Manufacturer" "Murata"
			(at 0 0 0)
			(unlocked yes)
			(layer "F.Fab")
			(hide yes)
			(effects
				(font
					(size 1 1)
					(thickness 0.15)
				)
			)
		)
		(property "License" "Apache-2.0"
			(at 0 0 0)
			(unlocked yes)
			(layer "F.Fab")
			(hide yes)
			(effects
				(font
					(size 1 1)
					(thickness 0.15)
				)
			)
		)
		(property "Author" "Antmicro"
			(at 0 0 0)
			(unlocked yes)
			(layer "F.Fab")
			(hide yes)
			(effects
				(font
					(size 1 1)
					(thickness 0.15)
				)
			)
		)
		(property "Val" "1u"
			(at 0 0 0)
			(unlocked yes)
			(layer "F.Fab")
			(hide yes)
			(effects
				(font
					(size 1 1)
					(thickness 0.15)
				)
			)
		)
		(property "Voltage" "25V"
			(at 0 0 0)
			(unlocked yes)
			(layer "F.Fab")
			(hide yes)
			(effects
				(font
					(size 1 1)
					(thickness 0.15)
				)
			)
		)
		(property "Dielectric" "X5R"
			(at 0 0 0)
			(unlocked yes)
			(layer "F.Fab")
			(hide yes)
			(effects
				(font
					(size 1 1)
					(thickness 0.15)
				)
			)
		)
		(sheetname "/Power/")
		(sheetfile "power.kicad_sch")
		(attr smd)
		(fp_rect
			(start -0.925 -0.47)
			(end 0.925 0.47)
			(stroke
				(width 0.05)
				(type default)
			)
			(fill no)
			(layer "F.CrtYd")
		)
		(fp_line
			(start -0.494 -0.25)
			(end 0.504 -0.25)
			(stroke
				(width 0.15)
				(type solid)
			)
			(layer "F.Fab")
		)
		(fp_line
			(start -0.494 0.248)
			(end -0.494 -0.25)
			(stroke
				(width 0.15)
				(type solid)
			)
			(layer "F.Fab")
		)
		(fp_line
			(start 0.504 -0.25)
			(end 0.504 0.248)
			(stroke
				(width 0.15)
				(type solid)
			)
			(layer "F.Fab")
		)
		(fp_line
			(start 0.504 0.248)
			(end -0.494 0.248)
			(stroke
				(width 0.15)
				(type solid)
			)
			(layer "F.Fab")
		)
		(fp_text user "License: Apache-2.0"
			(at -0.939 5.799 0)
			(layer "F.Fab")
			(effects
				(font
					(size 0.7 0.7)
					(thickness 0.15)
				)
				(justify left bottom)
			)
		)
		(fp_text user "${REFERENCE}"
			(at 0 0 0)
			(layer "F.Fab")
			(effects
				(font
					(size 0.7 0.7)
					(thickness 0.15)
				)
				(justify left bottom)
			)
		)
		(fp_text user "Author: Antmicro"
			(at -0.939 3.399 0)
			(layer "F.Fab")
			(effects
				(font
					(size 0.7 0.7)
					(thickness 0.15)
				)
				(justify left bottom)
			)
		)
		(pad "1" smd roundrect
			(at -0.48 0)
			(size 0.59 0.64)
			(layers "F.Cu" "F.Mask" "F.Paste")
			(roundrect_rratio 0.25)
			(net 66 "GND")
			(pintype "passive")
		)
		(pad "2" smd roundrect
			(at 0.48 0)
			(size 0.59 0.64)
			(layers "F.Cu" "F.Mask" "F.Paste")
			(roundrect_rratio 0.25)
			(net 88 "/Power/3V3_VCC")
			(pintype "passive")
		)
	)
	(footprint "antmicro-footprints:C_0402_1005Metric"
		(layer "F.Cu")
		(at 143.5 145 -90)
		(descr "Capacitor SMD 0402")
		(tags "capacitor SMD 0402")
		(property "Reference" "C13"
			(at -1 -0.8 90)
			(layer "F.SilkS")
			(effects
				(font
					(size 0.7 0.7)
					(thickness 0.15)
				)
				(justify right top)
			)
		)
		(property "Value" "C_100n_0402"
			(at -1.022927 2.155213 90)
			(layer "F.Fab")
			(effects
				(font
					(size 0.7 0.7)
					(thickness 0.15)
				)
				(justify right top)
			)
		)
		(property "Datasheet" "https://www.murata.com/products/productdetail?partno=GRM155R61H104KE14%23"
			(at 0 0 90)
			(layer "F.Fab")
			(hide yes)
			(effects
				(font
					(size 1.27 1.27)
					(thickness 0.15)
				)
			)
		)
		(property "Description" "SMD Multilayer Ceramic Capacitor, 0.1 µF, 50 V, 0402 [1005 Metric], ± 10%, X5R, GRM Series"
			(at 0 0 90)
			(layer "F.Fab")
			(hide yes)
			(effects
				(font
					(size 1.27 1.27)
					(thickness 0.15)
				)
			)
		)
		(property "MPN" "GRM155R61H104KE14D"
			(at 0 0 270)
			(unlocked yes)
			(layer "F.Fab")
			(hide yes)
			(effects
				(font
					(size 1 1)
					(thickness 0.15)
				)
			)
		)
		(property "Manufacturer" "Murata"
			(at 0 0 270)
			(unlocked yes)
			(layer "F.Fab")
			(hide yes)
			(effects
				(font
					(size 1 1)
					(thickness 0.15)
				)
			)
		)
		(property "License" "Apache-2.0"
			(at 0 0 270)
			(unlocked yes)
			(layer "F.Fab")
			(hide yes)
			(effects
				(font
					(size 1 1)
					(thickness 0.15)
				)
			)
		)
		(property "Author" "Antmicro"
			(at 0 0 270)
			(unlocked yes)
			(layer "F.Fab")
			(hide yes)
			(effects
				(font
					(size 1 1)
					(thickness 0.15)
				)
			)
		)
		(property "Val" "100n"
			(at 0 0 270)
			(unlocked yes)
			(layer "F.Fab")
			(hide yes)
			(effects
				(font
					(size 1 1)
					(thickness 0.15)
				)
			)
		)
		(property "Voltage" "50V"
			(at 0 0 270)
			(unlocked yes)
			(layer "F.Fab")
			(hide yes)
			(effects
				(font
					(size 1 1)
					(thickness 0.15)
				)
			)
		)
		(property "Dielectric" "X5R"
			(at 0 0 270)
			(unlocked yes)
			(layer "F.Fab")
			(hide yes)
			(effects
				(font
					(size 1 1)
					(thickness 0.15)
				)
			)
		)
		(sheetname "/Power/Ideal-diode-2/")
		(sheetfile "ideal-diode.kicad_sch")
		(attr smd)
		(fp_rect
			(start -0.925 -0.47)
			(end 0.925 0.47)
			(stroke
				(width 0.05)
				(type default)
			)
			(fill no)
			(layer "F.CrtYd")
		)
		(fp_line
			(start -0.494 0.248)
			(end -0.494 -0.25)
			(stroke
				(width 0.15)
				(type solid)
			)
			(layer "F.Fab")
		)
		(fp_line
			(start 0.504 0.248)
			(end -0.494 0.248)
			(stroke
				(width 0.15)
				(type solid)
			)
			(layer "F.Fab")
		)
		(fp_line
			(start -0.494 -0.25)
			(end 0.504 -0.25)
			(stroke
				(width 0.15)
				(type solid)
			)
			(layer "F.Fab")
		)
		(fp_line
			(start 0.504 -0.25)
			(end 0.504 0.248)
			(stroke
				(width 0.15)
				(type solid)
			)
			(layer "F.Fab")
		)
		(fp_text user "${REFERENCE}"
			(at 0 0 90)
			(layer "F.Fab")
			(effects
				(font
					(size 0.7 0.7)
					(thickness 0.15)
				)
				(justify right top)
			)
		)
		(fp_text user "License: Apache-2.0"
			(at -0.939 5.799 90)
			(layer "F.Fab")
			(effects
				(font
					(size 0.7 0.7)
					(thickness 0.15)
				)
				(justify right top)
			)
		)
		(fp_text user "Author: Antmicro"
			(at -0.939 3.399 90)
			(layer "F.Fab")
			(effects
				(font
					(size 0.7 0.7)
					(thickness 0.15)
				)
				(justify right top)
			)
		)
		(pad "1" smd roundrect
			(at -0.48 0 270)
			(size 0.59 0.64)
			(layers "F.Cu" "F.Mask" "F.Paste")
			(roundrect_rratio 0.25)
			(net 66 "GND")
			(pintype "passive")
		)
		(pad "2" smd roundrect
			(at 0.48 0 270)
			(size 0.59 0.64)
			(layers "F.Cu" "F.Mask" "F.Paste")
			(roundrect_rratio 0.25)
			(net 116 "/Power/Ideal-diode-2/VIN")
			(pintype "passive")
		)
	)
	(footprint "antmicro-footprints:MP_Pad6mm_Drill3.2mm"
		(layer "F.Cu")
		(at 156.4 162.8 -90)
		(property "Reference" "MP1"
			(at 0 0 90)
			(layer "F.SilkS")
			(hide yes)
			(effects
				(font
					(size 0.7 0.7)
					(thickness 0.15)
				)
				(justify right top)
			)
		)
		(property "Value" "MP_Pad6mm_Drill3.2mm"
			(at 0 3.899999 90)
			(layer "F.Fab")
			(effects
				(font
					(size 0.7 0.7)
					(thickness 0.15)
				)
				(justify right top)
			)
		)
		(property "Description" "Mechanical part"
			(at 0 0 90)
			(layer "F.Fab")
			(hide yes)
			(effects
				(font
					(size 1.27 1.27)
					(thickness 0.15)
				)
			)
		)
		(property "Author" "Antmicro"
			(at 0 0 270)
			(unlocked yes)
			(layer "F.Fab")
			(hide yes)
			(effects
				(font
					(size 1 1)
					(thickness 0.15)
				)
			)
		)
		(property "License" "Apache-2.0"
			(at 0 0 270)
			(unlocked yes)
			(layer "F.Fab")
			(hide yes)
			(effects
				(font
					(size 1 1)
					(thickness 0.15)
				)
			)
		)
		(sheetname "/")
		(sheetfile "oculink-to-pcie-adapter.kicad_sch")
		(attr exclude_from_pos_files exclude_from_bom)
		(fp_circle
			(center 0 0)
			(end 3.25 0)
			(stroke
				(width 0.05)
				(type default)
			)
			(fill no)
			(layer "F.CrtYd")
		)
		(fp_text user "License: Apache-2.0"
			(at -0.178 8.425001 90)
			(layer "F.Fab")
			(effects
				(font
					(size 0.7 0.7)
					(thickness 0.15)
				)
				(justify right top)
			)
		)
		(fp_text user "${REFERENCE}"
			(at 0 0 90)
			(layer "F.Fab")
			(effects
				(font
					(size 0.7 0.7)
					(thickness 0.15)
				)
				(justify right top)
			)
		)
		(fp_text user "Author: Antmicro"
			(at -0.178001 7.225 90)
			(layer "F.Fab")
			(effects
				(font
					(size 0.7 0.7)
					(thickness 0.15)
				)
				(justify right top)
			)
		)
		(pad "1" thru_hole circle
			(at 0 0 270)
			(size 6 6)
			(drill 3.2)
			(layers "*.Cu" "*.Mask")
			(remove_unused_layers no)
			(net 66 "GND")
			(pintype "passive")
		)
	)
)
